# S9S_MB_2U (Grand Teton) — schematic netlist excerpt (pin names and nets, part order shuffled) for the footprints in the layout excerpt that follows; sources: Cadence DE-HDL packaged netlist, KiCad conversion of 03242023_DA0F0TMBIJ0_F0T_Motherboard_J_brd_V01_OCP.brd

U265  INA230AIRGTR  IC  pkg QFN16_THXI  page 172
  A1  = INA230_5_A1
  A0  = INA230_5_A0
  ALERT  = P12V_SCM_ADC_ALERT_R
  SDA  = SMB_INA230_5_3V3AUX_SDA_R1
  SCL  = SMB_INA230_5_3V3AUX_SCL_R1
  NC0  = NC_INA230_5_NC0
  NC1  = NC_INA230_5_NC1
  NC2  = NC_INA230_5_NC2
  VS  = P3V3_AUX
  GND  = GND
  \bus\  = P12V_SCM_R
  \in-\  = VSENSE_P12V_INA230_5_INN
  \in+\  = VSENSE_P12V_INA230_5_INP
  NC3  = NC_INA230_5_NC3
  NC4  = NC_INA230_5_NC4
  NC5  = NC_INA230_5_NC5
  TH  = GND

(kicad_pcb
	(version 20260206)
	(generator "pcbnew")
	(generator_version "10.0")
	(general
		(thickness 1.6)
		(legacy_teardrops no)
	)
	(paper "A4")
	(title_block
		(title "03242023_DA0F0TMBIJ0_F0T_Motherboard_J_brd_V01_OCP.brd")
		(comment 1 "Grand Teton / footprints 3599-3599 of 6105")
	)
	(layers
		(0 "F.Cu" signal "TOP")
		(4 "In1.Cu" signal "GND")
		(6 "In2.Cu" signal "IN1")
		(8 "In3.Cu" signal "GND1")
		(10 "In4.Cu" signal "IN2")
		(12 "In5.Cu" signal "GND2")
		(14 "In6.Cu" signal "IN3")
		(16 "In7.Cu" signal "GND3")
		(18 "In8.Cu" signal "VCC")
		(20 "In9.Cu" signal "VCC1")
		(22 "In10.Cu" signal "GND4")
		(24 "In11.Cu" signal "IN4")
		(26 "In12.Cu" signal "GND5")
		(28 "In13.Cu" signal "IN5")
		(30 "In14.Cu" signal "GND6")
		(32 "In15.Cu" signal "IN6")
		(34 "In16.Cu" signal "GND7")
		(2 "B.Cu" signal "BOTTOM")
		(9 "F.Adhes" user "F.Adhesive")
		(11 "B.Adhes" user "B.Adhesive")
		(13 "F.Paste" user "Package Geometry/Pastemask Top")
		(15 "B.Paste" user "Package Geometry/Pastemask Bottom")
		(5 "F.SilkS" user "Ref Des/Silkscreen Top")
		(7 "B.SilkS" user "Ref Des/Silkscreen Bottom")
		(1 "F.Mask" user "Board Geometry/Soldermask Top")
		(3 "B.Mask" user "Board Geometry/Soldermask Bottom")
		(17 "Dwgs.User" user "User.Drawings")
		(19 "Cmts.User" user "User.Comments")
		(21 "Eco1.User" user "User.Eco1")
		(23 "Eco2.User" user "User.Eco2")
		(25 "Edge.Cuts" user "Board Geometry/Outline")
		(27 "Margin" user)
		(31 "F.CrtYd" user "Package Geometry/Place Bound Top")
		(29 "B.CrtYd" user "Package Geometry/Place Bound Bottom")
		(35 "F.Fab" user "Ref Des/Assembly Top")
		(33 "B.Fab" user "Ref Des/Assembly Bottom")
	)
	(footprint ""
		(layer "F.Cu")
		(at 209.172556 -34.772092 90)
		(property "Reference" "U265"
			(at 3.273806 -3.826256 0)
			(unlocked yes)
			(layer "F.SilkS")
			(effects
				(font
					(size 0.7874 0.5842)
					(thickness 0.1524)
				)
			)
		)
		(property "Value" ""
			(at 0 0 90)
			(layer "F.Fab")
			(effects
				(font
					(size 1.27 1.27)
				)
			)
		)
		(duplicate_pad_numbers_are_jumpers no)
		(fp_line
			(start 1.500124 -1.500124)
			(end 1.500124 -1.004062)
			(stroke
				(width 0.1524)
				(type default)
			)
			(layer "F.SilkS")
		)
		(fp_line
			(start 1.004062 -1.500124)
			(end 1.500124 -1.500124)
			(stroke
				(width 0.1524)
				(type default)
			)
			(layer "F.SilkS")
		)
		(fp_line
			(start -1.500124 -1.500124)
			(end -1.004062 -1.500124)
			(stroke
				(width 0.1524)
				(type default)
			)
			(layer "F.SilkS")
		)
		(fp_line
			(start -1.500124 -1.004062)
			(end -1.500124 -1.500124)
			(stroke
				(width 0.1524)
				(type default)
			)
			(layer "F.SilkS")
		)
		(fp_line
			(start 1.500124 1.004062)
			(end 1.500124 1.500124)
			(stroke
				(width 0.1524)
				(type default)
			)
			(layer "F.SilkS")
		)
		(fp_line
			(start 1.500124 1.500124)
			(end 1.004062 1.500124)
			(stroke
				(width 0.1524)
				(type default)
			)
			(layer "F.SilkS")
		)
		(fp_line
			(start -1.004062 1.500124)
			(end -1.500124 1.500124)
			(stroke
				(width 0.1524)
				(type default)
			)
			(layer "F.SilkS")
		)
		(fp_line
			(start -1.500124 1.500124)
			(end -1.500124 1.004062)
			(stroke
				(width 0.1524)
				(type default)
			)
			(layer "F.SilkS")
		)
		(fp_poly
			(pts
				(xy -2.15011 -2.265934) (xy -1.790954 -1.188212) (xy -2.868422 -1.547368)
			)
			(stroke
				(width 0)
				(type default)
			)
			(fill yes)
			(layer "F.SilkS")
		)
		(fp_line
			(start 1.500124 -1.500124)
			(end 1.500124 1.500124)
			(stroke
				(width 0.1)
				(type default)
			)
			(layer "F.Fab")
		)
		(fp_line
			(start -1.500124 -1.500124)
			(end 1.500124 -1.500124)
			(stroke
				(width 0.1)
				(type default)
			)
			(layer "F.Fab")
		)
		(fp_line
			(start 1.500124 1.500124)
			(end -1.500124 1.500124)
			(stroke
				(width 0.1)
				(type default)
			)
			(layer "F.Fab")
		)
		(fp_line
			(start -1.500124 1.500124)
			(end -1.500124 -1.500124)
			(stroke
				(width 0.1)
				(type default)
			)
			(layer "F.Fab")
		)
		(fp_poly
			(pts
				(xy -2.847848 -1.258062) (xy -2.847848 -0.242062) (xy -1.831848 -0.750062)
			)
			(stroke
				(width 0)
				(type default)
			)
			(fill yes)
			(layer "F.Fab")
		)
		(pad "1" smd rect
			(at -1.400048 -0.750062)
			(size 0.2286 0.6096)
			(layers "F.Cu" "F.Mask" "F.Paste")
			(net "INA230_5_A1")
		)
		(pad "2" smd rect
			(at -1.400048 -0.249936)
			(size 0.2286 0.6096)
			(layers "F.Cu" "F.Mask" "F.Paste")
			(net "INA230_5_A0")
		)
		(pad "3" smd rect
			(at -1.400048 0.249936)
			(size 0.2286 0.6096)
			(layers "F.Cu" "F.Mask" "F.Paste")
			(net "P12V_SCM_ADC_ALERT_R")
		)
		(pad "4" smd rect
			(at -1.400048 0.750062)
			(size 0.2286 0.6096)
			(layers "F.Cu" "F.Mask" "F.Paste")
			(net "SMB_INA230_5_3V3AUX_SDA_R1")
		)
		(pad "5" smd rect
			(at -0.750062 1.400048 90)
			(size 0.2286 0.6096)
			(layers "F.Cu" "F.Mask" "F.Paste")
			(net "SMB_INA230_5_3V3AUX_SCL_R1")
		)
		(pad "6" smd rect
			(at -0.249936 1.400048 90)
			(size 0.2286 0.6096)
			(layers "F.Cu" "F.Mask" "F.Paste")
			(net "NC_INA230_5_NC0")
		)
		(pad "7" smd rect
			(at 0.249936 1.400048 90)
			(size 0.2286 0.6096)
			(layers "F.Cu" "F.Mask" "F.Paste")
			(net "NC_INA230_5_NC1")
		)
		(pad "8" smd rect
			(at 0.750062 1.400048 90)
			(size 0.2286 0.6096)
			(layers "F.Cu" "F.Mask" "F.Paste")
			(net "NC_INA230_5_NC2")
		)
		(pad "9" smd rect
			(at 1.400048 0.750062)
			(size 0.2286 0.6096)
			(layers "F.Cu" "F.Mask" "F.Paste")
			(net "P3V3_AUX")
		)
		(pad "10" smd rect
			(at 1.400048 0.249936)
			(size 0.2286 0.6096)
			(layers "F.Cu" "F.Mask" "F.Paste")
			(net "GND")
		)
		(pad "11" smd rect
			(at 1.400048 -0.249936)
			(size 0.2286 0.6096)
			(layers "F.Cu" "F.Mask" "F.Paste")
			(net "P12V_SCM_R")
		)
		(pad "12" smd rect
			(at 1.400048 -0.750062)
			(size 0.2286 0.6096)
			(layers "F.Cu" "F.Mask" "F.Paste")
			(net "VSENSE_P12V_INA230_5_INN")
		)
		(pad "13" smd rect
			(at 0.750062 -1.400048 90)
			(size 0.2286 0.6096)
			(layers "F.Cu" "F.Mask" "F.Paste")
			(net "VSENSE_P12V_INA230_5_INP")
		)
		(pad "14" smd rect
			(at 0.249936 -1.400048 90)
			(size 0.2286 0.6096)
			(layers "F.Cu" "F.Mask" "F.Paste")
			(net "NC_INA230_5_NC3")
		)
		(pad "15" smd rect
			(at -0.249936 -1.400048 90)
			(size 0.2286 0.6096)
			(layers "F.Cu" "F.Mask" "F.Paste")
			(net "NC_INA230_5_NC4")
		)
		(pad "16" smd rect
			(at -0.750062 -1.400048 90)
			(size 0.2286 0.6096)
			(layers "F.Cu" "F.Mask" "F.Paste")
			(net "NC_INA230_5_NC5")
		)
		(pad "TH" smd rect
			(at 0 0 90)
			(size 1.7018 1.7018)
			(layers "F.Cu" "F.Mask" "F.Paste")
			(net "GND")
		)
		(zone
			(layer "F.Cu")
			(hatch none 0.5)
			(connect_pads
				(clearance 0)
			)
			(min_thickness 0.25)
			(keepout
				(tracks not_allowed)
				(vias allowed)
				(pads allowed)
				(copperpour not_allowed)
				(footprints allowed)
			)
			(placement
				(enabled no)
				(sheetname "")
			)
			(fill
				(thermal_gap 0.5)
				(thermal_bridge_width 0.5)
				(island_removal_mode 0)
			)
			(polygon
				(pts
					(xy 209.147156 -33.727644) (xy 208.128108 -33.727644) (xy 208.128108 -35.81654) (xy 210.217004 -35.81654)
					(xy 210.217004 -33.727644) (xy 209.172556 -33.727644) (xy 209.172556 -33.870392) (xy 210.074256 -33.870392)
					(xy 210.074256 -35.673792) (xy 208.270856 -35.673792) (xy 208.270856 -33.870392) (xy 209.147156 -33.870392)
				)
			)
		)
	)
)
